# T6G (Grand Teton) — schematic netlist excerpt (pin names and nets, part order shuffled) for the footprints in the layout excerpt that follows; sources: Cadence DE-HDL packaged netlist, KiCad conversion of 04192023_DAF0TMB3IC0_F0TG_MB_C_brd_V02_OCP.brd

R502  Q_RES  15 1% CHIP  pkg 0402LF  page 39 : A = M_C_CPU1_ALERT_N ; B = M_C_CPU1_ALERT_R_N
C788  Q_CAP  1UF 4V 20% X6S  pkg 0201  page 301 : A = P0V9_CPU0_RT2_2A ; B = GND
C343  Q_CAP  4.7UF 6.3V 20% X6S  pkg 0402  page 334 : A = P0V9_CPU1_RT1_2A ; B = GND

(kicad_pcb
	(version 20260206)
	(generator "pcbnew")
	(generator_version "10.0")
	(general
		(thickness 1.6)
		(legacy_teardrops no)
	)
	(paper "A4")
	(title_block
		(title "04192023_DAF0TMB3IC0_F0TG_MB_C_brd_V02_OCP.brd")
		(comment 1 "Grand Teton / footprints 5899-5901 of 8354")
	)
	(layers
		(0 "F.Cu" signal "TOP")
		(4 "In1.Cu" signal "GND")
		(6 "In2.Cu" signal "IN1")
		(8 "In3.Cu" signal "GND1")
		(10 "In4.Cu" signal "IN2")
		(12 "In5.Cu" signal "GND2")
		(14 "In6.Cu" signal "IN3")
		(16 "In7.Cu" signal "GND3")
		(18 "In8.Cu" signal "VCC")
		(20 "In9.Cu" signal "VCC1")
		(22 "In10.Cu" signal "GND4")
		(24 "In11.Cu" signal "IN4")
		(26 "In12.Cu" signal "GND5")
		(28 "In13.Cu" signal "IN5")
		(30 "In14.Cu" signal "GND6")
		(32 "In15.Cu" signal "IN6")
		(34 "In16.Cu" signal "GND7")
		(2 "B.Cu" signal "BOTTOM")
		(9 "F.Adhes" user "F.Adhesive")
		(11 "B.Adhes" user "B.Adhesive")
		(13 "F.Paste" user "Package Geometry/Pastemask Top")
		(15 "B.Paste" user "Package Geometry/Pastemask Bottom")
		(5 "F.SilkS" user "Ref Des/Silkscreen Top")
		(7 "B.SilkS" user "Ref Des/Silkscreen Bottom")
		(1 "F.Mask" user "Board Geometry/Soldermask Top")
		(3 "B.Mask" user "Board Geometry/Soldermask Bottom")
		(17 "Dwgs.User" user "User.Drawings")
		(19 "Cmts.User" user "User.Comments")
		(21 "Eco1.User" user "User.Eco1")
		(23 "Eco2.User" user "User.Eco2")
		(25 "Edge.Cuts" user "Board Geometry/Outline")
		(27 "Margin" user)
		(31 "F.CrtYd" user "Package Geometry/Place Bound Top")
		(29 "B.CrtYd" user "Package Geometry/Place Bound Bottom")
		(35 "F.Fab" user "Ref Des/Assembly Top")
		(33 "B.Fab" user "Ref Des/Assembly Bottom")
	)
	(footprint ""
		(layer "B.Cu")
		(at 93.11894 -390.560052 90)
		(property "Reference" "C343"
			(at 0 0 90)
			(layer "B.SilkS")
			(hide yes)
			(effects
				(font
					(size 1.27 1.27)
				)
				(justify mirror)
			)
		)
		(property "Value" ""
			(at 0 0 90)
			(layer "B.Fab")
			(effects
				(font
					(size 1.27 1.27)
				)
				(justify mirror)
			)
		)
		(duplicate_pad_numbers_are_jumpers no)
		(fp_line
			(start 0.7874 -0.4064)
			(end -0.7874 -0.4064)
			(stroke
				(width 0.1524)
				(type default)
			)
			(layer "B.SilkS")
		)
		(fp_line
			(start -0.7874 -0.4064)
			(end -0.7874 0.4064)
			(stroke
				(width 0.1524)
				(type default)
			)
			(layer "B.SilkS")
		)
		(fp_line
			(start 0.7874 0.4064)
			(end 0.7874 -0.4064)
			(stroke
				(width 0.1524)
				(type default)
			)
			(layer "B.SilkS")
		)
		(fp_line
			(start -0.7874 0.4064)
			(end 0.7874 0.4064)
			(stroke
				(width 0.1524)
				(type default)
			)
			(layer "B.SilkS")
		)
		(fp_line
			(start 0.67945 -0.305054)
			(end 0.12065 -0.305054)
			(stroke
				(width 0.1)
				(type default)
			)
			(layer "B.Fab")
		)
		(fp_line
			(start 0.12065 -0.305054)
			(end 0.12065 -0.2794)
			(stroke
				(width 0.1)
				(type default)
			)
			(layer "B.Fab")
		)
		(fp_line
			(start -0.12065 -0.3048)
			(end -0.67945 -0.3048)
			(stroke
				(width 0.1)
				(type default)
			)
			(layer "B.Fab")
		)
		(fp_line
			(start -0.67945 -0.3048)
			(end -0.67945 0.3048)
			(stroke
				(width 0.1)
				(type default)
			)
			(layer "B.Fab")
		)
		(fp_line
			(start 0.12065 -0.2794)
			(end -0.12065 -0.2794)
			(stroke
				(width 0.1)
				(type default)
			)
			(layer "B.Fab")
		)
		(fp_line
			(start -0.12065 -0.2794)
			(end -0.12065 -0.3048)
			(stroke
				(width 0.1)
				(type default)
			)
			(layer "B.Fab")
		)
		(fp_line
			(start 0.12065 0.2794)
			(end 0.12065 0.3048)
			(stroke
				(width 0.1)
				(type default)
			)
			(layer "B.Fab")
		)
		(fp_line
			(start -0.120396 0.2794)
			(end 0.12065 0.2794)
			(stroke
				(width 0.1)
				(type default)
			)
			(layer "B.Fab")
		)
		(fp_line
			(start 0.67945 0.3048)
			(end 0.67945 -0.305054)
			(stroke
				(width 0.1)
				(type default)
			)
			(layer "B.Fab")
		)
		(fp_line
			(start 0.12065 0.3048)
			(end 0.67945 0.3048)
			(stroke
				(width 0.1)
				(type default)
			)
			(layer "B.Fab")
		)
		(fp_line
			(start -0.120396 0.3048)
			(end -0.120396 0.2794)
			(stroke
				(width 0.1)
				(type default)
			)
			(layer "B.Fab")
		)
		(fp_line
			(start -0.67945 0.3048)
			(end -0.120396 0.3048)
			(stroke
				(width 0.1)
				(type default)
			)
			(layer "B.Fab")
		)
		(pad "1" smd circle
			(at 0.40005 0 270)
			(size 0 0)
			(layers "B.Cu" "B.Mask" "B.Paste")
			(net "P0V9_CPU1_RT1_2A")
		)
		(pad "2" smd circle
			(at -0.40005 0 270)
			(size 0 0)
			(layers "B.Cu" "B.Mask" "B.Paste")
			(net "GND")
		)
	)
	(footprint ""
		(layer "B.Cu")
		(at 45.336968 -244.085364 180)
		(property "Reference" "R502"
			(at 0 0 0)
			(layer "B.SilkS")
			(hide yes)
			(effects
				(font
					(size 1.27 1.27)
				)
				(justify mirror)
			)
		)
		(property "Value" ""
			(at 0 0 0)
			(layer "B.Fab")
			(effects
				(font
					(size 1.27 1.27)
				)
				(justify mirror)
			)
		)
		(duplicate_pad_numbers_are_jumpers no)
		(fp_line
			(start 0.7874 0.4064)
			(end 0.7874 -0.4064)
			(stroke
				(width 0.1524)
				(type default)
			)
			(layer "B.SilkS")
		)
		(fp_line
			(start 0.7874 -0.4064)
			(end -0.7874 -0.4064)
			(stroke
				(width 0.1524)
				(type default)
			)
			(layer "B.SilkS")
		)
		(fp_line
			(start -0.7874 0.4064)
			(end 0.7874 0.4064)
			(stroke
				(width 0.1524)
				(type default)
			)
			(layer "B.SilkS")
		)
		(fp_line
			(start -0.7874 -0.4064)
			(end -0.7874 0.4064)
			(stroke
				(width 0.1524)
				(type default)
			)
			(layer "B.SilkS")
		)
		(fp_line
			(start 0.67945 0.3048)
			(end 0.67945 -0.305054)
			(stroke
				(width 0.1)
				(type default)
			)
			(layer "B.Fab")
		)
		(fp_line
			(start 0.67945 -0.305054)
			(end 0.12065 -0.305054)
			(stroke
				(width 0.1)
				(type default)
			)
			(layer "B.Fab")
		)
		(fp_line
			(start 0.12065 0.3048)
			(end 0.67945 0.3048)
			(stroke
				(width 0.1)
				(type default)
			)
			(layer "B.Fab")
		)
		(fp_line
			(start 0.12065 0.2794)
			(end 0.12065 0.3048)
			(stroke
				(width 0.1)
				(type default)
			)
			(layer "B.Fab")
		)
		(fp_line
			(start 0.12065 -0.2794)
			(end -0.12065 -0.2794)
			(stroke
				(width 0.1)
				(type default)
			)
			(layer "B.Fab")
		)
		(fp_line
			(start 0.12065 -0.305054)
			(end 0.12065 -0.2794)
			(stroke
				(width 0.1)
				(type default)
			)
			(layer "B.Fab")
		)
		(fp_line
			(start -0.120396 0.3048)
			(end -0.120396 0.2794)
			(stroke
				(width 0.1)
				(type default)
			)
			(layer "B.Fab")
		)
		(fp_line
			(start -0.120396 0.2794)
			(end 0.12065 0.2794)
			(stroke
				(width 0.1)
				(type default)
			)
			(layer "B.Fab")
		)
		(fp_line
			(start -0.12065 -0.2794)
			(end -0.12065 -0.3048)
			(stroke
				(width 0.1)
				(type default)
			)
			(layer "B.Fab")
		)
		(fp_line
			(start -0.12065 -0.3048)
			(end -0.67945 -0.3048)
			(stroke
				(width 0.1)
				(type default)
			)
			(layer "B.Fab")
		)
		(fp_line
			(start -0.67945 0.3048)
			(end -0.120396 0.3048)
			(stroke
				(width 0.1)
				(type default)
			)
			(layer "B.Fab")
		)
		(fp_line
			(start -0.67945 -0.3048)
			(end -0.67945 0.3048)
			(stroke
				(width 0.1)
				(type default)
			)
			(layer "B.Fab")
		)
		(pad "1" smd circle
			(at 0.40005 0)
			(size 0 0)
			(layers "B.Cu" "B.Mask" "B.Paste")
			(net "M_C_CPU1_ALERT_N")
		)
		(pad "2" smd circle
			(at -0.40005 0)
			(size 0 0)
			(layers "B.Cu" "B.Mask" "B.Paste")
			(net "M_C_CPU1_ALERT_R_N")
		)
	)
	(footprint ""
		(layer "B.Cu")
		(at 418.606224 -395.148562 90)
		(property "Reference" "C788"
			(at 0 0 90)
			(layer "B.SilkS")
			(hide yes)
			(effects
				(font
					(size 1.27 1.27)
				)
				(justify mirror)
			)
		)
		(property "Value" ""
			(at 0 0 90)
			(layer "B.Fab")
			(effects
				(font
					(size 1.27 1.27)
				)
				(justify mirror)
			)
		)
		(duplicate_pad_numbers_are_jumpers no)
		(fp_line
			(start 0.299974 -0.150114)
			(end -0.299974 -0.150114)
			(stroke
				(width 0.1)
				(type default)
			)
			(layer "B.Fab")
		)
		(fp_line
			(start -0.299974 -0.150114)
			(end -0.299974 0.150114)
			(stroke
				(width 0.1)
				(type default)
			)
			(layer "B.Fab")
		)
		(fp_line
			(start 0.299974 0.150114)
			(end 0.299974 -0.150114)
			(stroke
				(width 0.1)
				(type default)
			)
			(layer "B.Fab")
		)
		(fp_line
			(start -0.299974 0.150114)
			(end 0.299974 0.150114)
			(stroke
				(width 0.1)
				(type default)
			)
			(layer "B.Fab")
		)
		(pad "1" smd rect
			(at 0.2667 0 270)
			(size 0.3048 0.381)
			(layers "B.Cu" "B.Mask" "B.Paste")
			(net "P0V9_CPU0_RT2_2A")
		)
		(pad "2" smd rect
			(at -0.2667 0 270)
			(size 0.3048 0.381)
			(layers "B.Cu" "B.Mask" "B.Paste")
			(net "GND")
		)
	)
)
